# BASEBOARD_FAB2 (Tioga Pass) — schematic netlist excerpt (pin names and nets, part order shuffled) for the footprints in the layout excerpt that follows; sources: Cadence DE-HDL packaged netlist, KiCad conversion of Wiwynn_Tioga_Pass_MB.brd

J9U1  SCONN288_H44441003  SCONN  pkg PIP  page 80
  \12v\(1)  = P12V_NVDIMM_GHJ
  VSS(93)  = GND
  DQ(4)  = M_H_DQ<4>
  VSS(92)  = GND
  DQ(0)  = M_H_DQ<0>
  VSS(91)  = GND
  DQS9P  = M_H_DQS_DP<9>
  DQS9N  = M_H_DQS_DN<9>
  VSS(90)  = GND
  DQ(6)  = M_H_DQ<6>
  VSS(89)  = GND
  DQ(2)  = M_H_DQ<2>
  VSS(88)  = GND
  DQ(12)  = M_H_DQ<12>
  VSS(87)  = GND
  DQ(8)  = M_H_DQ<8>
  VSS(86)  = GND
  DQS10P  = M_H_DQS_DP<10>
  DQS10N  = M_H_DQS_DN<10>
  VSS(85)  = GND
  DQ(14)  = M_H_DQ<14>
  VSS(84)  = GND
  DQ(10)  = M_H_DQ<10>
  VSS(83)  = GND
  DQ(20)  = M_H_DQ<20>
  VSS(82)  = GND
  DQ(16)  = M_H_DQ<16>
  VSS(81)  = GND
  DQS11P  = M_H_DQS_DP<11>
  DQS11N  = M_H_DQS_DN<11>
  VSS(80)  = GND
  DQ(22)  = M_H_DQ<22>
  VSS(79)  = GND
  DQ(18)  = M_H_DQ<18>
  VSS(78)  = GND
  DQ(28)  = M_H_DQ<28>
  VSS(77)  = GND
  DQ(24)  = M_H_DQ<24>
  VSS(76)  = GND
  DQS12P  = M_H_DQS_DP<12>
  DQS12N  = M_H_DQS_DN<12>
  VSS(75)  = GND
  DQ(30)  = M_H_DQ<30>
  VSS(74)  = GND
  DQ(26)  = M_H_DQ<26>
  VSS(73)  = GND
  CB(4)  = M_H_ECC<4>
  VSS(72)  = GND
  CB(0)  = M_H_ECC<0>
  VSS(71)  = GND
  DQS17P  = M_H_DQS_DP<17>
  DQS17N  = M_H_DQS_DN<17>
  VSS(70)  = GND
  CB(6)  = M_H_ECC<6>
  VSS(69)  = GND
  CB(2)  = M_H_ECC<2>
  VSS(68)  = GND
  RESET_N  = M_GHJ_RST_N
  VDD(25)  = PVDDQ_GHJ
  CKE(0)  = M_H_CKE<2>
  VDD(24)  = PVDDQ_GHJ
  ACT_N  = M_H_ACT_N
  BG(0)  = M_H_BG<0>
  VDD(23)  = PVDDQ_GHJ
  A12  = M_H_MA<12>
  A9  = M_H_MA<9>
  VDD(22)  = PVDDQ_GHJ
  A8  = M_H_MA<8>
  A6  = M_H_MA<6>
  VDD(21)  = PVDDQ_GHJ
  A3  = M_H_MA<3>
  A1  = M_H_MA<1>
  VDD(20)  = PVDDQ_GHJ
  CK0P  = M_H_CLK_DP<2>
  CK0N  = M_H_CLK_DN<2>
  VDD(19)  = PVDDQ_GHJ
  VTT(1)  = PVTT_GHJ
  EVENT_N  = FM_DIMM_EVENT_COD_N
  A0  = M_H_MA<0>
  VDD(18)  = PVDDQ_GHJ
  BA(0)  = M_H_BA<0>
  A16_RAS_N  = M_H_MA<16>
  VDD(17)  = PVDDQ_GHJ
  S0_N  = M_H_CS_N<4>
  VDD(16)  = PVDDQ_GHJ
  A15_CAS_N  = M_H_MA<15>
  ODT(0)  = M_H_ODT<2>
  VDD(15)  = PVDDQ_GHJ
  S1_N  = M_H_CS_N<5>
  VDD(14)  = PVDDQ_GHJ
  ODT(1)  = M_H_ODT<3>
  VDD(13)  = PVDDQ_GHJ
  S2_N_C(0)  = M_H_CS_N<6>
  VSS(67)  = GND
  DQ(36)  = M_H_DQ<36>
  VSS(66)  = GND
  DQ(32)  = M_H_DQ<32>
  VSS(65)  = GND
  DQS13P  = M_H_DQS_DP<13>
  DQS13N  = M_H_DQS_DN<13>
  VSS(64)  = GND
  DQ(38)  = M_H_DQ<38>
  VSS(63)  = GND
  DQ(34)  = M_H_DQ<34>
  VSS(62)  = GND
  DQ(44)  = M_H_DQ<44>
  VSS(61)  = GND
  DQ(40)  = M_H_DQ<40>
  VSS(60)  = GND
  DQS14P  = M_H_DQS_DP<14>
  DQS14N  = M_H_DQS_DN<14>
  VSS(59)  = GND
  DQ(46)  = M_H_DQ<46>
  VSS(58)  = GND
  DQ(42)  = M_H_DQ<42>
  VSS(57)  = GND
  DQ(52)  = M_H_DQ<52>
  VSS(56)  = GND
  DQ(48)  = M_H_DQ<48>
  VSS(55)  = GND
  DQS15P  = M_H_DQS_DP<15>
  DQS15N  = M_H_DQS_DN<15>
  VSS(54)  = GND
  DQ(54)  = M_H_DQ<54>
  VSS(53)  = GND
  DQ(50)  = M_H_DQ<50>
  VSS(52)  = GND
  DQ(60)  = M_H_DQ<60>
  VSS(51)  = GND
  DQ(56)  = M_H_DQ<56>
  VSS(50)  = GND
  DQS16P  = M_H_DQS_DP<16>
  DQS16N  = M_H_DQS_DN<16>
  VSS(49)  = GND
  DQ(62)  = M_H_DQ<62>
  VSS(48)  = GND
  DQ(58)  = M_H_DQ<58>
  VSS(47)  = GND
  SA(0)  = PVPP_GHJ
  SA(1)  = PVPP_GHJ
  SCL  = SMB_DDR_GHJ_VPP_SCL
  VPP(4)  = PVPP_GHJ
  VPP(3)  = PVPP_GHJ
  RFU(2)  = TP_CH_H_DIMM0_RFU_2
  \12v\(0)  = P12V_NVDIMM_GHJ
  VREFCA  = M_H_VREF
  VSS(46)  = GND
  DQ(5)  = M_H_DQ<5>
  VSS(45)  = GND
  DQ(1)  = M_H_DQ<1>
  VSS(44)  = GND
  DQS0N  = M_H_DQS_DN<0>
  DQS0P  = M_H_DQS_DP<0>
  VSS(43)  = GND
  DQ(7)  = M_H_DQ<7>
  VSS(42)  = GND
  DQ(3)  = M_H_DQ<3>
  VSS(41)  = GND
  DQ(13)  = M_H_DQ<13>
  VSS(40)  = GND
  DQ(9)  = M_H_DQ<9>
  VSS(39)  = GND
  DQS1N  = M_H_DQS_DN<1>
  DQS1P  = M_H_DQS_DP<1>
  VSS(38)  = GND
  DQ(15)  = M_H_DQ<15>
  VSS(37)  = GND
  DQ(11)  = M_H_DQ<11>
  VSS(36)  = GND
  DQ(21)  = M_H_DQ<21>
  VSS(35)  = GND
  DQ(17)  = M_H_DQ<17>
  VSS(34)  = GND
  DQS2N  = M_H_DQS_DN<2>
  DQS2P  = M_H_DQS_DP<2>
  VSS(33)  = GND
  DQ(23)  = M_H_DQ<23>
  VSS(32)  = GND
  DQ(19)  = M_H_DQ<19>
  VSS(31)  = GND
  DQ(29)  = M_H_DQ<29>
  VSS(30)  = GND
  DQ(25)  = M_H_DQ<25>
  VSS(29)  = GND
  DQS3N  = M_H_DQS_DN<3>
  DQS3P  = M_H_DQS_DP<3>
  VSS(28)  = GND
  DQ(31)  = M_H_DQ<31>
  VSS(27)  = GND
  DQ(27)  = M_H_DQ<27>
  VSS(26)  = GND
  CB(5)  = M_H_ECC<5>
  VSS(25)  = GND
  CB(1)  = M_H_ECC<1>
  VSS(24)  = GND
  DQS8N  = M_H_DQS_DN<8>
  DQS8P  = M_H_DQS_DP<8>
  VSS(23)  = GND
  CB(7)  = M_H_ECC<7>
  VSS(22)  = GND
  CB(3)  = M_H_ECC<3>
  VSS(21)  = GND
  CKE(1)  = M_H_CKE<3>
  VDD(12)  = PVDDQ_GHJ
  RFU(0)  = TP_CH_H_DIMM0_RFU_0
  VDD(11)  = PVDDQ_GHJ
  BG(1)  = M_H_BG<1>
  ALERT_N  = M_H_ALERT_N
  VDD(10)  = PVDDQ_GHJ
  A11  = M_H_MA<11>
  A7  = M_H_MA<7>
  VDD(9)  = PVDDQ_GHJ
  A5  = M_H_MA<5>
  A4  = M_H_MA<4>
  VDD(8)  = PVDDQ_GHJ
  A2  = M_H_MA<2>
  VDD(7)  = PVDDQ_GHJ
  CK1P  = M_H_CLK_DP<3>
  CK1N  = M_H_CLK_DN<3>
  VDD(6)  = PVDDQ_GHJ
  VTT(0)  = PVTT_GHJ
  PAR  = M_H_PAR
  VDD(5)  = PVDDQ_GHJ
  BA(1)  = M_H_BA<1>
  A10  = M_H_MA<10>
  VDD(4)  = PVDDQ_GHJ
  RFU(1)  = TP_CH_H_DIMM0_RFU_1
  A14_WE_N  = M_H_MA<14>
  VDD(3)  = PVDDQ_GHJ
  SAVE_N_NC  = FM_ADR_COMPLETE_GHJ_N
  VDD(2)  = PVDDQ_GHJ
  A13  = M_H_MA<13>
  VDD(1)  = PVDDQ_GHJ
  A17  = M_H_MA<17>
  C(2)  = M_H_C<2>
  VDD(0)  = PVDDQ_GHJ
  S3_N_C(1)  = M_H_CS_N<7>
  SA(2)  = GND
  VSS(20)  = GND
  DQ(37)  = M_H_DQ<37>
  VSS(19)  = GND
  DQ(33)  = M_H_DQ<33>
  VSS(18)  = GND
  DQS4N  = M_H_DQS_DN<4>
  DQS4P  = M_H_DQS_DP<4>
  VSS(17)  = GND
  DQ(39)  = M_H_DQ<39>
  VSS(16)  = GND
  DQ(35)  = M_H_DQ<35>
  VSS(15)  = GND
  DQ(45)  = M_H_DQ<45>
  VSS(14)  = GND
  DQ(41)  = M_H_DQ<41>
  VSS(13)  = GND
  DQS5N  = M_H_DQS_DN<5>
  DQS5P  = M_H_DQS_DP<5>
  VSS(12)  = GND
  DQ(47)  = M_H_DQ<47>
  VSS(11)  = GND
  DQ(43)  = M_H_DQ<43>
  VSS(10)  = GND
  DQ(53)  = M_H_DQ<53>
  VSS(9)  = GND
  DQ(49)  = M_H_DQ<49>
  VSS(8)  = GND
  DQS6N  = M_H_DQS_DN<6>
  DQS6P  = M_H_DQS_DP<6>
  VSS(7)  = GND
  DQ(55)  = M_H_DQ<55>
  VSS(6)  = GND
  DQ(51)  = M_H_DQ<51>
  VSS(5)  = GND
  DQ(61)  = M_H_DQ<61>
  VSS(4)  = GND
  DQ(57)  = M_H_DQ<57>
  VSS(3)  = GND
  DQS7N  = M_H_DQS_DN<7>
  DQS7P  = M_H_DQS_DP<7>
  VSS(2)  = GND
  DQ(63)  = M_H_DQ<63>
  VSS(1)  = GND
  DQ(59)  = M_H_DQ<59>
  VSS(0)  = GND
  VDDSPD  = PVPP_GHJ
  SDA  = SMB_DDR_GHJ_VPP_SDA
  VPP(1)  = PVPP_GHJ
  VPP(0)  = PVPP_GHJ
  VPP(2)  = PVPP_GHJ

(kicad_pcb
	(version 20260206)
	(generator "pcbnew")
	(generator_version "10.0")
	(general
		(thickness 1.6)
		(legacy_teardrops no)
	)
	(paper "A4")
	(title_block
		(title "Wiwynn_Tioga_Pass_MB.brd")
		(comment 1 "Tioga Pass / footprint 3114 of 4770 (J9U1), pads 152-201 of 291")
	)
	(layers
		(0 "F.Cu" signal "TOP")
		(4 "In1.Cu" signal "L2GND")
		(6 "In2.Cu" signal "L3")
		(8 "In3.Cu" signal "L4GND")
		(10 "In4.Cu" signal "L5")
		(12 "In5.Cu" signal "L6GND")
		(14 "In6.Cu" signal "L7VCC")
		(16 "In7.Cu" signal "L8VCC")
		(18 "In8.Cu" signal "L9GND")
		(20 "In9.Cu" signal "L10")
		(22 "In10.Cu" signal "L11GND")
		(24 "In11.Cu" signal "L12")
		(26 "In12.Cu" signal "L13GND")
		(2 "B.Cu" signal "BOTTOM")
		(9 "F.Adhes" user "F.Adhesive")
		(11 "B.Adhes" user "B.Adhesive")
		(13 "F.Paste" user "Package Geometry/Pastemask Top")
		(15 "B.Paste" user "Package Geometry/Pastemask Bottom")
		(5 "F.SilkS" user "Ref Des/Silkscreen Top")
		(7 "B.SilkS" user "Ref Des/Silkscreen Bottom")
		(1 "F.Mask" user "Board Geometry/Soldermask Top")
		(3 "B.Mask" user "Board Geometry/Soldermask Bottom")
		(17 "Dwgs.User" user "User.Drawings")
		(19 "Cmts.User" user "User.Comments")
		(21 "Eco1.User" user "User.Eco1")
		(23 "Eco2.User" user "User.Eco2")
		(25 "Edge.Cuts" user "Board Geometry/Outline")
		(27 "Margin" user)
		(31 "F.CrtYd" user "Package Geometry/Place Bound Top")
		(29 "B.CrtYd" user "Package Geometry/Place Bound Bottom")
		(35 "F.Fab" user "Ref Des/Assembly Top")
		(33 "B.Fab" user "Ref Des/Assembly Bottom")
	)
	(footprint ""
		(layer "B.Cu")
		(at 29.699458 -15.222982 90)
		(property "Reference" "J9U1"
			(at 2.276348 37.991542 0)
			(unlocked yes)
			(layer "B.SilkS")
			(effects
				(font
					(size 0.7874 0.5842)
					(thickness 0.1524)
				)
				(justify left mirror)
			)
		)
		(property "Value" ""
			(at 0 0 90)
			(layer "B.Fab")
			(effects
				(font
					(size 1.27 1.27)
				)
				(justify mirror)
			)
		)
		(duplicate_pad_numbers_are_jumpers no)
		(pad "149" smd rect
			(at -4.59994 3.400044 270)
			(size 1.8034 0.508)
			(layers "B.Cu" "B.Mask" "B.Paste")
			(net "GND")
		)
		(pad "150" smd rect
			(at -4.59994 4.249928 270)
			(size 1.8034 0.508)
			(layers "B.Cu" "B.Mask" "B.Paste")
			(net "M_H_DQ<1>")
		)
		(pad "151" smd rect
			(at -4.59994 5.100066 270)
			(size 1.8034 0.508)
			(layers "B.Cu" "B.Mask" "B.Paste")
			(net "GND")
		)
		(pad "152" smd rect
			(at -4.59994 5.94995 270)
			(size 1.8034 0.508)
			(layers "B.Cu" "B.Mask" "B.Paste")
			(net "M_H_DQS_DN<0>")
		)
		(pad "153" smd rect
			(at -4.59994 6.800088 270)
			(size 1.8034 0.508)
			(layers "B.Cu" "B.Mask" "B.Paste")
			(net "M_H_DQS_DP<0>")
		)
		(pad "154" smd rect
			(at -4.59994 7.649972 270)
			(size 1.8034 0.508)
			(layers "B.Cu" "B.Mask" "B.Paste")
			(net "GND")
		)
		(pad "155" smd rect
			(at -4.59994 8.50011 270)
			(size 1.8034 0.508)
			(layers "B.Cu" "B.Mask" "B.Paste")
			(net "M_H_DQ<7>")
		)
		(pad "156" smd rect
			(at -4.59994 9.349994 270)
			(size 1.8034 0.508)
			(layers "B.Cu" "B.Mask" "B.Paste")
			(net "GND")
		)
		(pad "157" smd rect
			(at -4.59994 10.199878 270)
			(size 1.8034 0.508)
			(layers "B.Cu" "B.Mask" "B.Paste")
			(net "M_H_DQ<3>")
		)
		(pad "158" smd rect
			(at -4.59994 11.050016 270)
			(size 1.8034 0.508)
			(layers "B.Cu" "B.Mask" "B.Paste")
			(net "GND")
		)
		(pad "159" smd rect
			(at -4.59994 11.8999 270)
			(size 1.8034 0.508)
			(layers "B.Cu" "B.Mask" "B.Paste")
			(net "M_H_DQ<13>")
		)
		(pad "160" smd rect
			(at -4.59994 12.750038 270)
			(size 1.8034 0.508)
			(layers "B.Cu" "B.Mask" "B.Paste")
			(net "GND")
		)
		(pad "161" smd rect
			(at -4.59994 13.599922 270)
			(size 1.8034 0.508)
			(layers "B.Cu" "B.Mask" "B.Paste")
			(net "M_H_DQ<9>")
		)
		(pad "162" smd rect
			(at -4.59994 14.45006 270)
			(size 1.8034 0.508)
			(layers "B.Cu" "B.Mask" "B.Paste")
			(net "GND")
		)
		(pad "163" smd rect
			(at -4.59994 15.299944 270)
			(size 1.8034 0.508)
			(layers "B.Cu" "B.Mask" "B.Paste")
			(net "M_H_DQS_DN<1>")
		)
		(pad "164" smd rect
			(at -4.59994 16.150082 270)
			(size 1.8034 0.508)
			(layers "B.Cu" "B.Mask" "B.Paste")
			(net "M_H_DQS_DP<1>")
		)
		(pad "165" smd rect
			(at -4.59994 16.999966 270)
			(size 1.8034 0.508)
			(layers "B.Cu" "B.Mask" "B.Paste")
			(net "GND")
		)
		(pad "166" smd rect
			(at -4.59994 17.850104 270)
			(size 1.8034 0.508)
			(layers "B.Cu" "B.Mask" "B.Paste")
			(net "M_H_DQ<15>")
		)
		(pad "167" smd rect
			(at -4.59994 18.699988 270)
			(size 1.8034 0.508)
			(layers "B.Cu" "B.Mask" "B.Paste")
			(net "GND")
		)
		(pad "168" smd rect
			(at -4.59994 19.550126 270)
			(size 1.8034 0.508)
			(layers "B.Cu" "B.Mask" "B.Paste")
			(net "M_H_DQ<11>")
		)
		(pad "169" smd rect
			(at -4.59994 20.40001 270)
			(size 1.8034 0.508)
			(layers "B.Cu" "B.Mask" "B.Paste")
			(net "GND")
		)
		(pad "170" smd rect
			(at -4.59994 21.249894 270)
			(size 1.8034 0.508)
			(layers "B.Cu" "B.Mask" "B.Paste")
			(net "M_H_DQ<21>")
		)
		(pad "171" smd rect
			(at -4.59994 22.100032 270)
			(size 1.8034 0.508)
			(layers "B.Cu" "B.Mask" "B.Paste")
			(net "GND")
		)
		(pad "172" smd rect
			(at -4.59994 22.949916 270)
			(size 1.8034 0.508)
			(layers "B.Cu" "B.Mask" "B.Paste")
			(net "M_H_DQ<17>")
		)
		(pad "173" smd rect
			(at -4.59994 23.800054 270)
			(size 1.8034 0.508)
			(layers "B.Cu" "B.Mask" "B.Paste")
			(net "GND")
		)
		(pad "174" smd rect
			(at -4.59994 24.649938 270)
			(size 1.8034 0.508)
			(layers "B.Cu" "B.Mask" "B.Paste")
			(net "M_H_DQS_DN<2>")
		)
		(pad "175" smd rect
			(at -4.59994 25.500076 270)
			(size 1.8034 0.508)
			(layers "B.Cu" "B.Mask" "B.Paste")
			(net "M_H_DQS_DP<2>")
		)
		(pad "176" smd rect
			(at -4.59994 26.34996 270)
			(size 1.8034 0.508)
			(layers "B.Cu" "B.Mask" "B.Paste")
			(net "GND")
		)
		(pad "177" smd rect
			(at -4.59994 27.200098 270)
			(size 1.8034 0.508)
			(layers "B.Cu" "B.Mask" "B.Paste")
			(net "M_H_DQ<23>")
		)
		(pad "178" smd rect
			(at -4.59994 28.049982 270)
			(size 1.8034 0.508)
			(layers "B.Cu" "B.Mask" "B.Paste")
			(net "GND")
		)
		(pad "179" smd rect
			(at -4.59994 28.90012 270)
			(size 1.8034 0.508)
			(layers "B.Cu" "B.Mask" "B.Paste")
			(net "M_H_DQ<19>")
		)
		(pad "180" smd rect
			(at -4.59994 29.750004 270)
			(size 1.8034 0.508)
			(layers "B.Cu" "B.Mask" "B.Paste")
			(net "GND")
		)
		(pad "181" smd rect
			(at -4.59994 30.599888 270)
			(size 1.8034 0.508)
			(layers "B.Cu" "B.Mask" "B.Paste")
			(net "M_H_DQ<29>")
		)
		(pad "182" smd rect
			(at -4.59994 31.450026 270)
			(size 1.8034 0.508)
			(layers "B.Cu" "B.Mask" "B.Paste")
			(net "GND")
		)
		(pad "183" smd rect
			(at -4.59994 32.29991 270)
			(size 1.8034 0.508)
			(layers "B.Cu" "B.Mask" "B.Paste")
			(net "M_H_DQ<25>")
		)
		(pad "184" smd rect
			(at -4.59994 33.150048 270)
			(size 1.8034 0.508)
			(layers "B.Cu" "B.Mask" "B.Paste")
			(net "GND")
		)
		(pad "185" smd rect
			(at -4.59994 33.999932 270)
			(size 1.8034 0.508)
			(layers "B.Cu" "B.Mask" "B.Paste")
			(net "M_H_DQS_DN<3>")
		)
		(pad "186" smd rect
			(at -4.59994 34.85007 270)
			(size 1.8034 0.508)
			(layers "B.Cu" "B.Mask" "B.Paste")
			(net "M_H_DQS_DP<3>")
		)
		(pad "187" smd rect
			(at -4.59994 35.699954 270)
			(size 1.8034 0.508)
			(layers "B.Cu" "B.Mask" "B.Paste")
			(net "GND")
		)
		(pad "188" smd rect
			(at -4.59994 36.550092 270)
			(size 1.8034 0.508)
			(layers "B.Cu" "B.Mask" "B.Paste")
			(net "M_H_DQ<31>")
		)
		(pad "189" smd rect
			(at -4.59994 37.399976 270)
			(size 1.8034 0.508)
			(layers "B.Cu" "B.Mask" "B.Paste")
			(net "GND")
		)
		(pad "190" smd rect
			(at -4.59994 38.250114 270)
			(size 1.8034 0.508)
			(layers "B.Cu" "B.Mask" "B.Paste")
			(net "M_H_DQ<27>")
		)
		(pad "191" smd rect
			(at -4.59994 39.099998 270)
			(size 1.8034 0.508)
			(layers "B.Cu" "B.Mask" "B.Paste")
			(net "GND")
		)
		(pad "192" smd rect
			(at -4.59994 39.949882 270)
			(size 1.8034 0.508)
			(layers "B.Cu" "B.Mask" "B.Paste")
			(net "M_H_ECC<5>")
		)
		(pad "193" smd rect
			(at -4.59994 40.80002 270)
			(size 1.8034 0.508)
			(layers "B.Cu" "B.Mask" "B.Paste")
			(net "GND")
		)
		(pad "194" smd rect
			(at -4.59994 41.649904 270)
			(size 1.8034 0.508)
			(layers "B.Cu" "B.Mask" "B.Paste")
			(net "M_H_ECC<1>")
		)
		(pad "195" smd rect
			(at -4.59994 42.500042 270)
			(size 1.8034 0.508)
			(layers "B.Cu" "B.Mask" "B.Paste")
			(net "GND")
		)
		(pad "196" smd rect
			(at -4.59994 43.349926 270)
			(size 1.8034 0.508)
			(layers "B.Cu" "B.Mask" "B.Paste")
			(net "M_H_DQS_DN<8>")
		)
		(pad "197" smd rect
			(at -4.59994 44.200064 270)
			(size 1.8034 0.508)
			(layers "B.Cu" "B.Mask" "B.Paste")
			(net "M_H_DQS_DP<8>")
		)
		(pad "198" smd rect
			(at -4.59994 45.049948 270)
			(size 1.8034 0.508)
			(layers "B.Cu" "B.Mask" "B.Paste")
			(net "GND")
		)
	)
)
